(kicad_pcb
	(version 20241229)
	(generator "pcbnew")
	(generator_version "9.0")
	(general
		(thickness 1.62)
		(legacy_teardrops no)
	)
	(paper "A4")
	(title_block
		(title "OCuLink to 10GbE adapter")
		(date "2026-02-23")
		(rev "1.1.0")
		(company "Antmicro Ltd")
		(comment 1 "www.antmicro.com")
		(comment 9 "footprints 286-291 of 510")
	)
	(layers
		(0 "F.Cu" signal)
		(4 "In1.Cu" signal)
		(6 "In2.Cu" signal)
		(8 "In3.Cu" signal)
		(10 "In4.Cu" signal)
		(12 "In5.Cu" signal)
		(14 "In6.Cu" signal)
		(2 "B.Cu" signal)
		(9 "F.Adhes" user "F.Adhesive")
		(11 "B.Adhes" user "B.Adhesive")
		(13 "F.Paste" user)
		(15 "B.Paste" user)
		(5 "F.SilkS" user "F.Silkscreen")
		(7 "B.SilkS" user "B.Silkscreen")
		(1 "F.Mask" user)
		(3 "B.Mask" user)
		(17 "Dwgs.User" user "User.Drawings")
		(19 "Cmts.User" user "User.Comments")
		(21 "Eco1.User" user "User.Eco1")
		(23 "Eco2.User" user "User.Eco2")
		(25 "Edge.Cuts" user)
		(27 "Margin" user)
		(31 "F.CrtYd" user "F.Courtyard")
		(29 "B.CrtYd" user "B.Courtyard")
		(35 "F.Fab" user)
		(33 "B.Fab" user)
	)
	(footprint "antmicro-footprints:R_0402_1005Metric"
		(layer "B.Cu")
		(at 96.45 101.1)
		(descr "Resistor SMD 0402")
		(tags "resistor SMD 0402")
		(property "Reference" "R62"
			(at 0.9 -0.316667 0)
			(layer "B.SilkS")
			(effects
				(font
					(size 0.7 0.7)
					(thickness 0.15)
				)
				(justify right top mirror)
			)
		)
		(property "Value" "R_3k3_0402"
			(at -1.011843 -1.772046 0)
			(layer "B.Fab")
			(hide yes)
			(effects
				(font
					(size 0.7 0.7)
					(thickness 0.15)
				)
				(justify right top mirror)
			)
		)
		(property "Datasheet" "https://www.bourns.com/docs/product-datasheets/cr.pdf"
			(at 0 0 0)
			(layer "B.Fab")
			(hide yes)
			(effects
				(font
					(size 1.27 1.27)
					(thickness 0.15)
				)
				(justify mirror)
			)
		)
		(property "Description" "SMD Chip Resistor, 3.3 kohm, ± 1%, 63 mW, 0402 [1005 Metric], Thick Film, General Purpose"
			(at 0 0 0)
			(layer "B.Fab")
			(hide yes)
			(effects
				(font
					(size 1.27 1.27)
					(thickness 0.15)
				)
				(justify mirror)
			)
		)
		(property "MPN" "CR0402-FX-3301GLF"
			(at 0 0 0)
			(unlocked yes)
			(layer "B.Fab")
			(hide yes)
			(effects
				(font
					(size 1 1)
					(thickness 0.15)
				)
				(justify mirror)
			)
		)
		(property "Manufacturer" "Bourns"
			(at 0 0 0)
			(unlocked yes)
			(layer "B.Fab")
			(hide yes)
			(effects
				(font
					(size 1 1)
					(thickness 0.15)
				)
				(justify mirror)
			)
		)
		(property "License" "Apache-2.0"
			(at 0 0 0)
			(unlocked yes)
			(layer "B.Fab")
			(hide yes)
			(effects
				(font
					(size 1 1)
					(thickness 0.15)
				)
				(justify mirror)
			)
		)
		(property "Author" "Antmicro"
			(at 0 0 0)
			(unlocked yes)
			(layer "B.Fab")
			(hide yes)
			(effects
				(font
					(size 1 1)
					(thickness 0.15)
				)
				(justify mirror)
			)
		)
		(property "Val" "3k3"
			(at 0 0 0)
			(unlocked yes)
			(layer "B.Fab")
			(hide yes)
			(effects
				(font
					(size 1 1)
					(thickness 0.15)
				)
				(justify mirror)
			)
		)
		(property "Tolerance" "1%"
			(at 0 0 0)
			(unlocked yes)
			(layer "B.Fab")
			(hide yes)
			(effects
				(font
					(size 1 1)
					(thickness 0.15)
				)
				(justify mirror)
			)
		)
		(sheetname "/X710-AT2 10GbE/")
		(sheetfile "x710-at2-10gbe.kicad_sch")
		(attr smd)
		(fp_rect
			(start -0.925 0.47)
			(end 0.925 -0.47)
			(stroke
				(width 0.05)
				(type default)
			)
			(fill no)
			(layer "B.CrtYd")
		)
		(fp_rect
			(start -0.5 0.25)
			(end 0.5 -0.25)
			(stroke
				(width 0.15)
				(type solid)
			)
			(fill no)
			(layer "B.Fab")
		)
		(pad "1" smd roundrect
			(at -0.48 0)
			(size 0.59 0.64)
			(layers "B.Cu" "B.Mask" "B.Paste")
			(roundrect_rratio 0.25)
			(net 101 "/X710-AT2 10GbE/MDIO2_SDA2")
			(pintype "passive")
		)
		(pad "2" smd roundrect
			(at 0.48 0)
			(size 0.59 0.64)
			(layers "B.Cu" "B.Mask" "B.Paste")
			(roundrect_rratio 0.25)
			(net 7 "+3V3")
			(pintype "passive")
		)
	)
	(footprint "antmicro-footprints:R_0402_1005Metric"
		(layer "B.Cu")
		(at 106.2 70.25 -90)
		(descr "Resistor SMD 0402")
		(tags "resistor SMD 0402")
		(property "Reference" "R92"
			(at 0.9 -0.48 90)
			(layer "B.SilkS")
			(effects
				(font
					(size 0.7 0.7)
					(thickness 0.15)
				)
				(justify left bottom mirror)
			)
		)
		(property "Value" "R_10k_0402"
			(at -1.011843 -1.772046 90)
			(layer "B.Fab")
			(hide yes)
			(effects
				(font
					(size 0.7 0.7)
					(thickness 0.15)
				)
				(justify left bottom mirror)
			)
		)
		(property "Datasheet" "https://www.bourns.com/docs/product-datasheets/cr.pdf"
			(at 0 0 90)
			(layer "B.Fab")
			(hide yes)
			(effects
				(font
					(size 1.27 1.27)
					(thickness 0.15)
				)
				(justify mirror)
			)
		)
		(property "Description" "SMD Chip Resistor, 10 kohm, ± 1%, 62.5 mW, 0402 [1005 Metric], Thick Film, General Purpose"
			(at 0 0 90)
			(layer "B.Fab")
			(hide yes)
			(effects
				(font
					(size 1.27 1.27)
					(thickness 0.15)
				)
				(justify mirror)
			)
		)
		(property "MPN" "CR0402-FX-1002GLF"
			(at 0 0 270)
			(unlocked yes)
			(layer "B.Fab")
			(hide yes)
			(effects
				(font
					(size 1 1)
					(thickness 0.15)
				)
				(justify mirror)
			)
		)
		(property "Manufacturer" "Bourns"
			(at 0 0 270)
			(unlocked yes)
			(layer "B.Fab")
			(hide yes)
			(effects
				(font
					(size 1 1)
					(thickness 0.15)
				)
				(justify mirror)
			)
		)
		(property "License" "Apache-2.0"
			(at 0 0 270)
			(unlocked yes)
			(layer "B.Fab")
			(hide yes)
			(effects
				(font
					(size 1 1)
					(thickness 0.15)
				)
				(justify mirror)
			)
		)
		(property "Author" "Antmicro"
			(at 0 0 270)
			(unlocked yes)
			(layer "B.Fab")
			(hide yes)
			(effects
				(font
					(size 1 1)
					(thickness 0.15)
				)
				(justify mirror)
			)
		)
		(property "Val" "10k"
			(at 0 0 270)
			(unlocked yes)
			(layer "B.Fab")
			(hide yes)
			(effects
				(font
					(size 1 1)
					(thickness 0.15)
				)
				(justify mirror)
			)
		)
		(property "Tolerance" "1%"
			(at 0 0 270)
			(unlocked yes)
			(layer "B.Fab")
			(hide yes)
			(effects
				(font
					(size 1 1)
					(thickness 0.15)
				)
				(justify mirror)
			)
		)
		(sheetname "/X710-AT2 Misc/")
		(sheetfile "x710-at2-mics.kicad_sch")
		(attr smd)
		(fp_rect
			(start -0.925 0.47)
			(end 0.925 -0.47)
			(stroke
				(width 0.05)
				(type default)
			)
			(fill no)
			(layer "B.CrtYd")
		)
		(fp_rect
			(start -0.5 0.25)
			(end 0.5 -0.25)
			(stroke
				(width 0.15)
				(type solid)
			)
			(fill no)
			(layer "B.Fab")
		)
		(pad "1" smd roundrect
			(at -0.48 0 270)
			(size 0.59 0.64)
			(layers "B.Cu" "B.Mask" "B.Paste")
			(roundrect_rratio 0.25)
			(net 394 "/OCuLink/SMBus.SCL")
			(pintype "passive")
		)
		(pad "2" smd roundrect
			(at 0.48 0 270)
			(size 0.59 0.64)
			(layers "B.Cu" "B.Mask" "B.Paste")
			(roundrect_rratio 0.25)
			(net 7 "+3V3")
			(pintype "passive")
		)
	)
	(footprint "antmicro-footprints:R_0402_1005Metric"
		(layer "B.Cu")
		(at 95.95 96.5 -90)
		(descr "Resistor SMD 0402")
		(tags "resistor SMD 0402")
		(property "Reference" "R99"
			(at 1.15 -3.35 90)
			(layer "B.SilkS")
			(effects
				(font
					(size 0.7 0.7)
					(thickness 0.15)
				)
				(justify right bottom mirror)
			)
		)
		(property "Value" "R_10k_0402"
			(at -1.011843 -1.772046 90)
			(layer "B.Fab")
			(hide yes)
			(effects
				(font
					(size 0.7 0.7)
					(thickness 0.15)
				)
				(justify left bottom mirror)
			)
		)
		(property "Datasheet" "https://www.bourns.com/docs/product-datasheets/cr.pdf"
			(at 0 0 90)
			(layer "B.Fab")
			(hide yes)
			(effects
				(font
					(size 1.27 1.27)
					(thickness 0.15)
				)
				(justify mirror)
			)
		)
		(property "Description" "SMD Chip Resistor, 10 kohm, ± 1%, 62.5 mW, 0402 [1005 Metric], Thick Film, General Purpose"
			(at 0 0 90)
			(layer "B.Fab")
			(hide yes)
			(effects
				(font
					(size 1.27 1.27)
					(thickness 0.15)
				)
				(justify mirror)
			)
		)
		(property "MPN" "CR0402-FX-1002GLF"
			(at 0 0 270)
			(unlocked yes)
			(layer "B.Fab")
			(hide yes)
			(effects
				(font
					(size 1 1)
					(thickness 0.15)
				)
				(justify mirror)
			)
		)
		(property "Manufacturer" "Bourns"
			(at 0 0 270)
			(unlocked yes)
			(layer "B.Fab")
			(hide yes)
			(effects
				(font
					(size 1 1)
					(thickness 0.15)
				)
				(justify mirror)
			)
		)
		(property "License" "Apache-2.0"
			(at 0 0 270)
			(unlocked yes)
			(layer "B.Fab")
			(hide yes)
			(effects
				(font
					(size 1 1)
					(thickness 0.15)
				)
				(justify mirror)
			)
		)
		(property "Author" "Antmicro"
			(at 0 0 270)
			(unlocked yes)
			(layer "B.Fab")
			(hide yes)
			(effects
				(font
					(size 1 1)
					(thickness 0.15)
				)
				(justify mirror)
			)
		)
		(property "Val" "10k"
			(at 0 0 270)
			(unlocked yes)
			(layer "B.Fab")
			(hide yes)
			(effects
				(font
					(size 1 1)
					(thickness 0.15)
				)
				(justify mirror)
			)
		)
		(property "Tolerance" "1%"
			(at 0 0 270)
			(unlocked yes)
			(layer "B.Fab")
			(hide yes)
			(effects
				(font
					(size 1 1)
					(thickness 0.15)
				)
				(justify mirror)
			)
		)
		(sheetname "/X710-AT2 Misc/")
		(sheetfile "x710-at2-mics.kicad_sch")
		(attr smd)
		(fp_rect
			(start -0.925 0.47)
			(end 0.925 -0.47)
			(stroke
				(width 0.05)
				(type default)
			)
			(fill no)
			(layer "B.CrtYd")
		)
		(fp_rect
			(start -0.5 0.25)
			(end 0.5 -0.25)
			(stroke
				(width 0.15)
				(type solid)
			)
			(fill no)
			(layer "B.Fab")
		)
		(pad "1" smd roundrect
			(at -0.48 0 270)
			(size 0.59 0.64)
			(layers "B.Cu" "B.Mask" "B.Paste")
			(roundrect_rratio 0.25)
			(net 289 "/X710-AT2 Misc/~{PCI_DIS}")
			(pintype "passive")
		)
		(pad "2" smd roundrect
			(at 0.48 0 270)
			(size 0.59 0.64)
			(layers "B.Cu" "B.Mask" "B.Paste")
			(roundrect_rratio 0.25)
			(net 7 "+3V3")
			(pintype "passive")
		)
	)
	(footprint "antmicro-footprints:R_0402_1005Metric"
		(layer "B.Cu")
		(at 106.2 68.15 -90)
		(descr "Resistor SMD 0402")
		(tags "resistor SMD 0402")
		(property "Reference" "R162"
			(at -3.64 -0.44 90)
			(layer "B.SilkS")
			(effects
				(font
					(size 0.7 0.7)
					(thickness 0.15)
				)
				(justify left bottom mirror)
			)
		)
		(property "Value" "R_0R_0402"
			(at -1.011843 -1.772046 90)
			(layer "B.Fab")
			(hide yes)
			(effects
				(font
					(size 0.7 0.7)
					(thickness 0.15)
				)
				(justify left bottom mirror)
			)
		)
		(property "Datasheet" "https://industrial.panasonic.com/cdbs/www-data/pdf/RDA0000/AOA0000C301.pdf"
			(at 0 0 90)
			(layer "B.Fab")
			(hide yes)
			(effects
				(font
					(size 1.27 1.27)
					(thickness 0.15)
				)
				(justify mirror)
			)
		)
		(property "Description" "SMD Chip Resistor, Jumper, 0 ohm, 100 mW, 0402 [1005 Metric], Thick Film, General Purpose"
			(at 0 0 90)
			(layer "B.Fab")
			(hide yes)
			(effects
				(font
					(size 1.27 1.27)
					(thickness 0.15)
				)
				(justify mirror)
			)
		)
		(property "MPN" "ERJ2GE0R00X"
			(at 0 0 270)
			(unlocked yes)
			(layer "B.Fab")
			(hide yes)
			(effects
				(font
					(size 1 1)
					(thickness 0.15)
				)
				(justify mirror)
			)
		)
		(property "Manufacturer" "Panasonic"
			(at 0 0 270)
			(unlocked yes)
			(layer "B.Fab")
			(hide yes)
			(effects
				(font
					(size 1 1)
					(thickness 0.15)
				)
				(justify mirror)
			)
		)
		(property "License" "Apache-2.0"
			(at 0 0 270)
			(unlocked yes)
			(layer "B.Fab")
			(hide yes)
			(effects
				(font
					(size 1 1)
					(thickness 0.15)
				)
				(justify mirror)
			)
		)
		(property "Author" "Antmicro"
			(at 0 0 270)
			(unlocked yes)
			(layer "B.Fab")
			(hide yes)
			(effects
				(font
					(size 1 1)
					(thickness 0.15)
				)
				(justify mirror)
			)
		)
		(property "Val" "0R"
			(at 0 0 270)
			(unlocked yes)
			(layer "B.Fab")
			(hide yes)
			(effects
				(font
					(size 1 1)
					(thickness 0.15)
				)
				(justify mirror)
			)
		)
		(property "Tolerance" "~"
			(at 0 0 270)
			(unlocked yes)
			(layer "B.Fab")
			(hide yes)
			(effects
				(font
					(size 1 1)
					(thickness 0.15)
				)
				(justify mirror)
			)
		)
		(property "Current" "1A"
			(at 0 0 270)
			(unlocked yes)
			(layer "B.Fab")
			(hide yes)
			(effects
				(font
					(size 1 1)
					(thickness 0.15)
				)
				(justify mirror)
			)
		)
		(sheetname "/OCuLink/")
		(sheetfile "oculink.kicad_sch")
		(attr smd)
		(fp_rect
			(start -0.925 0.47)
			(end 0.925 -0.47)
			(stroke
				(width 0.05)
				(type default)
			)
			(fill no)
			(layer "B.CrtYd")
		)
		(fp_rect
			(start -0.5 0.25)
			(end 0.5 -0.25)
			(stroke
				(width 0.15)
				(type solid)
			)
			(fill no)
			(layer "B.Fab")
		)
		(pad "1" smd roundrect
			(at -0.48 0 270)
			(size 0.59 0.64)
			(layers "B.Cu" "B.Mask" "B.Paste")
			(roundrect_rratio 0.25)
			(net 304 "/OCuLink/SCL")
			(pintype "passive")
		)
		(pad "2" smd roundrect
			(at 0.48 0 270)
			(size 0.59 0.64)
			(layers "B.Cu" "B.Mask" "B.Paste")
			(roundrect_rratio 0.25)
			(net 394 "/OCuLink/SMBus.SCL")
			(pintype "passive")
		)
	)
	(footprint "antmicro-footprints:C_0402_1005Metric"
		(layer "B.Cu")
		(at 91.2 96.45 -90)
		(descr "Capacitor SMD 0402")
		(tags "capacitor SMD 0402")
		(property "Reference" "C121"
			(at -14.39 -0.412657 90)
			(layer "B.SilkS")
			(effects
				(font
					(size 0.7 0.7)
					(thickness 0.15)
				)
				(justify left bottom mirror)
			)
		)
		(property "Value" "C_1u_25V_0402"
			(at -1.022927 -2.155213 90)
			(layer "B.Fab")
			(hide yes)
			(effects
				(font
					(size 0.7 0.7)
					(thickness 0.15)
				)
				(justify left bottom mirror)
			)
		)
		(property "Datasheet" "https://www.murata.com/products/productdetail?partno=GRM155R61E105KE11%23"
			(at 0 0 90)
			(layer "B.Fab")
			(hide yes)
			(effects
				(font
					(size 1.27 1.27)
					(thickness 0.15)
				)
				(justify mirror)
			)
		)
		(property "Description" "SMD Multilayer Ceramic Capacitor, 1 µF, 25 V, 0402 [1005 Metric], ± 10%, X5R, GRM Series"
			(at 0 0 90)
			(layer "B.Fab")
			(hide yes)
			(effects
				(font
					(size 1.27 1.27)
					(thickness 0.15)
				)
				(justify mirror)
			)
		)
		(property "MPN" "GRM155R61E105KE11J"
			(at 0 0 270)
			(unlocked yes)
			(layer "B.Fab")
			(hide yes)
			(effects
				(font
					(size 1 1)
					(thickness 0.15)
				)
				(justify mirror)
			)
		)
		(property "Manufacturer" "Murata"
			(at 0 0 270)
			(unlocked yes)
			(layer "B.Fab")
			(hide yes)
			(effects
				(font
					(size 1 1)
					(thickness 0.15)
				)
				(justify mirror)
			)
		)
		(property "License" "Apache-2.0"
			(at 0 0 270)
			(unlocked yes)
			(layer "B.Fab")
			(hide yes)
			(effects
				(font
					(size 1 1)
					(thickness 0.15)
				)
				(justify mirror)
			)
		)
		(property "Author" "Antmicro"
			(at 0 0 270)
			(unlocked yes)
			(layer "B.Fab")
			(hide yes)
			(effects
				(font
					(size 1 1)
					(thickness 0.15)
				)
				(justify mirror)
			)
		)
		(property "Val" "1u"
			(at 0 0 270)
			(unlocked yes)
			(layer "B.Fab")
			(hide yes)
			(effects
				(font
					(size 1 1)
					(thickness 0.15)
				)
				(justify mirror)
			)
		)
		(property "Voltage" "25V"
			(at 0 0 270)
			(unlocked yes)
			(layer "B.Fab")
			(hide yes)
			(effects
				(font
					(size 1 1)
					(thickness 0.15)
				)
				(justify mirror)
			)
		)
		(property "Dielectric" "X5R"
			(at 0 0 270)
			(unlocked yes)
			(layer "B.Fab")
			(hide yes)
			(effects
				(font
					(size 1 1)
					(thickness 0.15)
				)
				(justify mirror)
			)
		)
		(sheetname "/X710-AT2 power/")
		(sheetfile "x710-at2-power.kicad_sch")
		(attr smd)
		(fp_rect
			(start -0.925 0.47)
			(end 0.925 -0.47)
			(stroke
				(width 0.05)
				(type default)
			)
			(fill no)
			(layer "B.CrtYd")
		)
		(fp_line
			(start -0.494 0.25)
			(end 0.504 0.25)
			(stroke
				(width 0.15)
				(type solid)
			)
			(layer "B.Fab")
		)
		(fp_line
			(start 0.504 0.25)
			(end 0.504 -0.248)
			(stroke
				(width 0.15)
				(type solid)
			)
			(layer "B.Fab")
		)
		(fp_line
			(start -0.494 -0.248)
			(end -0.494 0.25)
			(stroke
				(width 0.15)
				(type solid)
			)
			(layer "B.Fab")
		)
		(fp_line
			(start 0.504 -0.248)
			(end -0.494 -0.248)
			(stroke
				(width 0.15)
				(type solid)
			)
			(layer "B.Fab")
		)
		(pad "1" smd roundrect
			(at -0.48 0 270)
			(size 0.59 0.64)
			(layers "B.Cu" "B.Mask" "B.Paste")
			(roundrect_rratio 0.25)
			(net 28 "GND")
			(pintype "passive")
		)
		(pad "2" smd roundrect
			(at 0.48 0 270)
			(size 0.59 0.64)
			(layers "B.Cu" "B.Mask" "B.Paste")
			(roundrect_rratio 0.25)
			(net 9 "VCCD")
			(pintype "passive")
		)
	)
	(footprint "antmicro-footprints:TP_SMD_1mm"
		(layer "B.Cu")
		(at 84.74 74.55 -90)
		(property "Reference" "TP35"
			(at -1.13 9.818102 90)
			(layer "B.SilkS")
			(effects
				(font
					(size 0.7 0.7)
					(thickness 0.15)
				)
				(justify left bottom mirror)
			)
		)
		(property "Value" "TP_1mm_SMD"
			(at 0 -1.4 90)
			(layer "B.Fab")
			(hide yes)
			(effects
				(font
					(size 0.7 0.7)
					(thickness 0.15)
				)
				(justify left bottom mirror)
			)
		)
		(property "Description" "Test point 1mm SMD"
			(at 0 0 90)
			(layer "B.Fab")
			(hide yes)
			(effects
				(font
					(size 1.27 1.27)
					(thickness 0.15)
				)
				(justify mirror)
			)
		)
		(property "MPN" ""
			(at 0 0 90)
			(unlocked yes)
			(layer "B.Fab")
			(hide yes)
			(effects
				(font
					(size 1 1)
					(thickness 0.15)
				)
				(justify mirror)
			)
		)
		(property "Manufacturer" ""
			(at 0 0 90)
			(unlocked yes)
			(layer "B.Fab")
			(hide yes)
			(effects
				(font
					(size 1 1)
					(thickness 0.15)
				)
				(justify mirror)
			)
		)
		(property "Author" "Antmicro"
			(at 0 0 90)
			(unlocked yes)
			(layer "B.Fab")
			(hide yes)
			(effects
				(font
					(size 1 1)
					(thickness 0.15)
				)
				(justify mirror)
			)
		)
		(property "License" "Apache-2.0"
			(at 0 0 90)
			(unlocked yes)
			(layer "B.Fab")
			(hide yes)
			(effects
				(font
					(size 1 1)
					(thickness 0.15)
				)
				(justify mirror)
			)
		)
		(sheetname "/X710-AT2 power/")
		(sheetfile "x710-at2-power.kicad_sch")
		(attr exclude_from_pos_files exclude_from_bom)
		(fp_circle
			(center 0 0)
			(end 0.6 0)
			(stroke
				(width 0.05)
				(type default)
			)
			(fill no)
			(layer "B.CrtYd")
		)
		(pad "1" smd circle
			(at 0 0 270)
			(size 1 1)
			(layers "B.Cu" "B.Mask")
			(net 1 "VCCA")
			(pinfunction "1")
			(pintype "passive")
		)
	)
)
